FILE_TYPE = CONNECTIVITY;
{Allegro Design Entry HDL 17.4-2019 S026 (4007227) 1/17/2022}
"PAGE_NUMBER" = 13;
0"NC";
1"M_D_CPU0_SB_DQS_DP<9:0>";
2"M_D_CPU0_SB_CA<6:0>";
3"M_D_CPU0_SA_CA<6:0>";
4"M_D_CPU0_SB_DQS_DN<9:0>";
5"M_D_CPU0_SA_DQS_DN<9:0>";
6"M_D_CPU0_SA_DQS_DP<9:0>";
7"M_D_CPU0_SB_CB<7:0>";
8"M_D_CPU0_SB_DQ<31:0>";
9"M_D_CPU0_SA_CB<7:0>";
10"M_D_CPU0_SA_DQ<31:0>";
11"M_D_CPU0_ALERT_N";
12"M_D_CPU0_ALERT_R_N";
13"M_D_CPU0_SA_DQS_DN<2>";
14"M_D_CPU0_SB_DQS_DP<7>";
15"M_D_CPU0_SB_CA<5>";
16"M_D_CPU0_SA_DQ<25>";
17"M_D_CPU0_SA_DQ<27>";
18"M_D_CPU0_SA_DQ<18>";
19"M_D_CPU0_SA_DQ<17>";
20"M_D_CPU0_SA_DQ<16>";
21"M_D_CPU0_SA_DQ<15>";
22"M_D_CPU0_SA_DQS_DP<1>";
23"M_D_CPU0_SA_DQ<21>";
24"M_D_CPU0_SA_DQ<3>";
25"M_D_CPU0_SA_DQ<4>";
26"M_D_CPU0_SA_DQ<5>";
27"M_D_CPU0_SA_DQ<6>";
28"M_D_CPU0_SA_DQ<7>";
29"M_D_CPU0_SA_DQ<8>";
30"M_D_CPU0_SA_DQ<9>";
31"M_D_CPU0_SA_DQ<10>";
32"M_D_CPU0_SA_DQ<11>";
33"M_D_CPU0_SA_DQ<12>";
34"M_D_CPU0_SA_DQ<13>";
35"M_D_CPU0_SA_DQ<14>";
36"M_D_CPU0_SA_DQ<0>";
37"M_D_CPU0_SA_DQ<1>";
38"M_D_CPU0_SA_DQ<2>";
39"M_D_CPU0_SB_DQ<2>";
40"M_D_CPU0_SA_DQ<29>";
41"M_D_CPU0_SA_DQ<19>";
42"M_D_CPU0_SA_DQ<30>";
43"M_D_CPU0_SA_DQ<31>";
44"M_D_CPU0_SA_DQ<20>";
45"M_D_CPU0_SA_DQ<22>";
46"M_D_CPU0_SA_DQ<23>";
47"M_D_CPU0_SA_DQ<24>";
48"M_D_CPU0_SA_DQ<26>";
49"M_D_CPU0_SB_DQ<0>";
50"M_D_CPU0_SB_DQ<1>";
51"M_D_CPU0_SA_DQ<28>";
52"M_D_CPU0_SB_DQ<12>";
53"M_D_CPU0_SB_DQ<13>";
54"M_D_CPU0_SB_DQ<3>";
55"M_D_CPU0_SB_DQ<14>";
56"M_D_CPU0_SB_DQ<4>";
57"M_D_CPU0_SB_DQ<15>";
58"M_D_CPU0_SB_DQ<5>";
59"M_D_CPU0_SB_DQ<16>";
60"M_D_CPU0_SB_DQ<6>";
61"M_D_CPU0_SB_DQ<17>";
62"M_D_CPU0_SB_DQ<7>";
63"M_D_CPU0_SB_DQ<18>";
64"M_D_CPU0_SB_DQ<8>";
65"M_D_CPU0_SB_DQ<19>";
66"M_D_CPU0_SB_DQ<9>";
67"M_D_CPU0_SB_DQ<20>";
68"M_D_CPU0_SB_DQ<21>";
69"M_D_CPU0_SB_DQ<10>";
70"M_D_CPU0_SB_DQ<11>";
71"M_D_CPU0_SB_DQ<23>";
72"M_D_CPU0_SB_DQ<24>";
73"M_D_CPU0_SB_DQ<25>";
74"M_D_CPU0_SB_DQ<26>";
75"M_D_CPU0_SB_DQ<27>";
76"M_D_CPU0_SB_DQ<28>";
77"M_D_CPU0_SB_DQ<29>";
78"M_D_CPU0_SA_CB<0>";
79"M_D_CPU0_SA_CB<1>";
80"M_D_CPU0_SA_CB<2>";
81"M_D_CPU0_SA_CB<3>";
82"M_D_CPU0_SA_CB<4>";
83"M_D_CPU0_SB_DQ<30>";
84"M_D_CPU0_SA_CB<5>";
85"M_D_CPU0_SB_DQ<31>";
86"M_D_CPU0_SA_CB<6>";
87"M_D_CPU0_SA_CB<7>";
88"M_D_CPU0_SB_DQ<22>";
89"M_D_CPU0_SB_CB<3>";
90"M_D_CPU0_SB_CB<4>";
91"M_D_CPU0_SB_CB<5>";
92"M_D_CPU0_SB_CB<6>";
93"M_D_CPU0_SB_CB<7>";
94"M_D_CPU0_SB_CB<0>";
95"M_D_CPU0_SB_CB<1>";
96"M_D_CPU0_SB_CB<2>";
97"M_D_CPU0_SA_DQS_DN<5>";
98"M_D_CPU0_SA_DQS_DN<6>";
99"M_D_CPU0_SA_DQS_DP<2>";
100"M_D_CPU0_SA_DQS_DN<7>";
101"M_D_CPU0_SA_DQS_DP<3>";
102"M_D_CPU0_SA_DQS_DN<8>";
103"M_D_CPU0_SA_DQS_DP<4>";
104"M_D_CPU0_SA_DQS_DP<5>";
105"M_D_CPU0_SA_DQS_DP<6>";
106"M_D_CPU0_SA_DQS_DP<7>";
107"M_D_CPU0_SA_DQS_DP<8>";
108"M_D_CPU0_SA_DQS_DP<9>";
109"M_D_CPU0_SA_DQS_DN<0>";
110"M_D_CPU0_SA_DQS_DN<1>";
111"M_D_CPU0_SA_DQS_DN<3>";
112"M_D_CPU0_SA_DQS_DN<4>";
113"M_D_CPU0_SA_DQS_DP<0>";
114"M_D_CPU0_SB_DQS_DN<0>";
115"M_D_CPU0_SB_DQS_DN<1>";
116"M_D_CPU0_SB_DQS_DN<2>";
117"M_D_CPU0_SB_DQS_DN<3>";
118"M_D_CPU0_SA_DQS_DN<9>";
119"M_D_CPU0_SB_DQS_DN<4>";
120"M_D_CPU0_SB_DQS_DP<0>";
121"M_D_CPU0_SB_DQS_DN<5>";
122"M_D_CPU0_SB_DQS_DP<1>";
123"M_D_CPU0_SB_DQS_DN<6>";
124"M_D_CPU0_SB_DQS_DP<2>";
125"M_D_CPU0_SB_DQS_DN<7>";
126"M_D_CPU0_SB_DQS_DP<3>";
127"M_D_CPU0_SB_DQS_DN<8>";
128"M_D_CPU0_SB_DQS_DP<4>";
129"M_D_CPU0_SB_DQS_DP<5>";
130"M_D_CPU0_SB_DQS_DP<6>";
131"M_D_CPU0_SB_DQS_DP<8>";
132"M_D_CPU0_SA_CA<0>";
133"M_D_CPU0_SB_CA<0>";
134"M_D_CPU0_SA_CA<1>";
135"M_D_CPU0_SB_CA<1>";
136"M_D_CPU0_SA_CA<2>";
137"M_D_CPU0_SB_CA<2>";
138"M_D_CPU0_SA_CA<3>";
139"M_D_CPU0_SB_DQS_DN<9>";
140"M_D_CPU0_SA_CA<4>";
141"M_D_CPU0_SB_CA<4>";
142"M_D_CPU0_SA_CA<5>";
143"M_D_CPU0_SA_CA<6>";
144"M_D_CPU0_SB_CA<6>";
145"M_D_CPU0_SB_CA<3>";
146"M_D_CPU0_SB_DQS_DP<9>";
147"M_D_CPU0_RESET_N";
148"M_D_CPU0_SB_PAR";
149"M_D_CPU0_SB_RSP<0>";
150"M_D_CPU0_SB_CS_N<1>";
151"M_D_CPU0_SB_CS_N<0>";
152"M_D_CPU0_SA_PAR";
153"M_D_CPU0_SA_RSP<0>";
154"M_D_CPU0_SA_CS_N<1>";
155"M_D_CPU0_SA_CS_N<0>";
156"M_D_CPU0_CLK_DN<0>";
157"M_D_CPU0_CLK_DP<0>";
158"TP_M_D_CPU0_SA_TEST39D";
%"GENOA_SP5"
"4","(-4600,3650)","0","pure_quanta","I159";
;
LOCATION"U25"
$SEC"4"
CDS_SEC"4"
VALUE"SOCKET6096_13568-001"
MATERIAL"IO"
PART_TYPE"SMLF"
NEEDS_NO_SIZE"TRUE"
CDS_LMAN_SYM_OUTLINE"-650,2525,650,-2525"
CDS_LIB"pure_quanta"
PART_NUMBER"DGA^6000030";
"TEST39D"
$PN"BF58"158;
"MD1_CLK_L"
$PN"BG60"0;
"MD1_CLK_H"
$PN"BF60"0;
"MD0_CLK_L"
$PN"BD60"156;
"MD0_CLK_H"
$PN"BC60"157;
"MDB_DQS_H9"
$PN"BV60"146;
"MDB_CA3"
$PN"BJ60"145;
"MDB_PAR"
$PN"BL60"148;
"MDA_PAR"
$PN"BC59"152;
"MDA1_RSP_L"
$PN"BP58"0;
"MDA_DATA2"
$PN"F60"38;
"MDA_DATA17"
$PN"V58"19;
"MDA_DATA28"
$PN"AG60"51;
"MDA_DQS_H0"
$PN"G60"113;
"MDA_DQS_L4"
$PN"AM60"112;
"MDB_CHECK2"
$PN"CA60"96;
"MDB_DATA1"
$PN"CC59"50;
"MDB_DATA11"
$PN"CK58"70;
"MDB_DATA22"
$PN"CW60"88;
"MDA0_RSP_L"
$PN"BN59"153;
"MDA_CHECK7"
$PN"AR59"87;
"MDA_DATA1"
$PN"F58"37;
"MDA_DATA16"
$PN"U60"20;
"MDA_DATA27"
$PN"AE59"17;
"MDA_DQS_L3"
$PN"AF60"111;
"MDB_CHECK1"
$PN"CA59"95;
"MDB_DATA0"
$PN"CB60"49;
"MDB_DATA10"
$PN"CJ60"69;
"MDB_DATA21"
$PN"CW59"68;
"MDA_CHECK6"
$PN"AP60"86;
"MDA_DATA0"
$PN"E60"36;
"MDA_DATA15"
$PN"U59"21;
"MDA_DATA26"
$PN"AD60"48;
"MDA_DQS_L2"
$PN"Y60"13;
"MDB1_CS_L1"
$PN"BM60"0;
"MDB_CHECK0"
$PN"BY60"94;
"MDB_DATA20"
$PN"CV60"67;
"MDB_DATA31"
$PN"DF60"85;
"MDA_CHECK5"
$PN"AP58"84;
"MDA_DATA14"
$PN"T60"35;
"MDA_DATA25"
$PN"AD58"16;
"MDA_DQS_L1"
$PN"P60"110;
"MDB0_CS_L1"
$PN"BN60"150;
"MDB1_CS_L0"
$PN"BL59"0;
"MDB_CA6"
$PN"BK60"144;
"MDB_DATA30"
$PN"DE60"83;
"MDB_DQS_H8"
$PN"DD58"131;
"MDA_CA6"
$PN"BB58"143;
"MDA_CHECK4"
$PN"AN60"82;
"MDA_DATA13"
$PN"T58"34;
"MDA_DATA24"
$PN"AC60"47;
"MDA_DQS_L0"
$PN"H60"109;
"MDB0_CS_L0"
$PN"BM58"151;
"MDB_CA5"
$PN"BK58"15;
"MDB_DQS_H7"
$PN"CV58"14;
"MDA_CA5"
$PN"BB60"142;
"MDA_CHECK3"
$PN"AL59"81;
"MDA_DATA12"
$PN"R60"33;
"MDA_DATA23"
$PN"AC59"46;
"MDB_CA4"
$PN"BJ59"141;
"MDB_DQS_H6"
$PN"CM58"130;
"MDA_CA4"
$PN"BA60"140;
"MDA_CHECK2"
$PN"AK60"80;
"MDA_DATA11"
$PN"N59"32;
"MDA_DATA22"
$PN"AB60"45;
"MDB_DQS_H5"
$PN"CF58"129;
"MDB_DQS_L9"
$PN"BW60"139;
"MDA_CA3"
$PN"BA59"138;
"MDA_CHECK1"
$PN"AK58"79;
"MDA_DATA10"
$PN"M60"31;
"MDA_DATA21"
$PN"AB58"23;
"MDB_CA2"
$PN"BH60"137;
"MDB_DQS_H4"
$PN"BY58"128;
"MDB_DQS_L8"
$PN"DC59"127;
"MDA1_CS_L1"
$PN"AV58"0;
"MDA_CA2"
$PN"AY58"136;
"MDA_CHECK0"
$PN"AJ60"78;
"MDA_DATA20"
$PN"AA60"44;
"MDA_DATA31"
$PN"AJ59"43;
"MDA_DQS_H9"
$PN"AN59"108;
"MDB_CA1"
$PN"BH58"135;
"MDB_DQS_H3"
$PN"DB60"126;
"MDB_DQS_L7"
$PN"CU59"125;
"MDA0_CS_L1"
$PN"AW59"154;
"MDA1_CS_L0"
$PN"AU60"0;
"MDA_CA1"
$PN"AY60"134;
"MDA_DATA30"
$PN"AH60"42;
"MDA_DQS_H8"
$PN"AG59"107;
"MDB_CA0"
$PN"BG59"133;
"MDB_DATA9"
$PN"CJ59"66;
"MDB_DATA19"
$PN"CT58"65;
"MDB_DQS_H2"
$PN"CT60"124;
"MDB_DQS_L6"
$PN"CL59"123;
"MDA0_CS_L0"
$PN"AV60"155;
"MDA_CA0"
$PN"AW60"132;
"MDA_DATA9"
$PN"M58"30;
"MDA_DQS_H7"
$PN"AA59"106;
"MDB_DATA8"
$PN"CH60"64;
"MDB_DATA18"
$PN"CR60"63;
"MDB_DATA29"
$PN"DE59"77;
"MDB_DQS_H1"
$PN"CK60"122;
"MDB_DQS_L5"
$PN"CE59"121;
"MDA_DATA8"
$PN"L60"29;
"MDA_DQS_H6"
$PN"R59"105;
"MDB1_RSP_L"
$PN"BR60"0;
"MDB_DATA7"
$PN"CH58"62;
"MDB_DATA17"
$PN"CR59"61;
"MDB_DATA28"
$PN"DD60"76;
"MDB_DQS_H0"
$PN"CD60"120;
"MDB_DQS_L4"
$PN"BW59"119;
"MDA_DATA7"
$PN"L59"28;
"MDA_DQS_H5"
$PN"J59"104;
"MDA_DQS_L9"
$PN"AM58"118;
"MDB0_RSP_L"
$PN"BP60"149;
"MDB_CHECK7"
$PN"BV58"93;
"MDB_DATA6"
$PN"CG60"60;
"MDB_DATA16"
$PN"CP60"59;
"MDB_DATA27"
$PN"DB58"75;
"MDB_DQS_L3"
$PN"DC60"117;
"MDA_DATA6"
$PN"K60"27;
"MDA_DQS_H4"
$PN"AL60"103;
"MDA_DQS_L8"
$PN"AF58"102;
"MDB_CHECK6"
$PN"BU60"92;
"MDB_DATA5"
$PN"CG59"58;
"MDB_DATA15"
$PN"CP58"57;
"MDB_DATA26"
$PN"DA60"74;
"MDB_DQS_L2"
$PN"CU60"116;
"MDA_DATA5"
$PN"K58"26;
"MDA_DQS_H3"
$PN"AE60"101;
"MDA_DQS_L7"
$PN"Y58"100;
"MDB_CHECK5"
$PN"BU59"91;
"MDB_DATA4"
$PN"CF60"56;
"MDB_DATA14"
$PN"CN60"55;
"MDB_DATA25"
$PN"DA59"73;
"MDB_DQS_L1"
$PN"CL60"115;
"MDA_DATA4"
$PN"J60"25;
"MDA_DATA19"
$PN"W59"41;
"MDA_DQS_H2"
$PN"W60"99;
"MDA_DQS_L6"
$PN"P58"98;
"MDB_CHECK4"
$PN"BT60"90;
"MDB_DATA3"
$PN"CD58"54;
"MDB_DATA13"
$PN"CN59"53;
"MDB_DATA24"
$PN"CY60"72;
"MDB_DQS_L0"
$PN"CE60"114;
"MDA_DATA3"
$PN"G59"24;
"MDA_DATA18"
$PN"V60"18;
"MDA_DATA29"
$PN"AH58"40;
"MDA_DQS_H1"
$PN"N60"22;
"MDA_DQS_L5"
$PN"H58"97;
"MDB_CHECK3"
$PN"CB58"89;
"MDB_DATA2"
$PN"CC60"39;
"MDB_DATA12"
$PN"CM60"52;
"MDB_DATA23"
$PN"CY58"71;
"MD_RESET_L"
$PN"AU59"147;
"MD_ALERT_L"
$PN"AT58"12;
%"TAP"
"1","(-3325,5925)","0","mstr_standard","I162";
;
CDS_LIB"mstr_standard"
BODY_TYPE"PLUMBING"
HDL_TAP"TRUE";
"B \NAC \NWC"10;
"S \NAC"
BN"2"38;
%"TAP"
"1","(-3325,6025)","0","mstr_standard","I163";
;
CDS_LIB"mstr_standard"
BODY_TYPE"PLUMBING"
HDL_TAP"TRUE";
"B \NAC \NWC"10;
"S \NAC"
BN"0"36;
%"TAP"
"1","(-3325,5975)","0","mstr_standard","I164";
;
CDS_LIB"mstr_standard"
BODY_TYPE"PLUMBING"
HDL_TAP"TRUE";
"B \NAC \NWC"10;
"S \NAC"
BN"1"37;
%"TAP"
"1","(-3325,5775)","0","mstr_standard","I165";
;
CDS_LIB"mstr_standard"
BODY_TYPE"PLUMBING"
HDL_TAP"TRUE";
"B \NAC \NWC"10;
"S \NAC"
BN"5"26;
%"TAP"
"1","(-3325,5875)","0","mstr_standard","I166";
;
CDS_LIB"mstr_standard"
BODY_TYPE"PLUMBING"
HDL_TAP"TRUE";
"B \NAC \NWC"10;
"S \NAC"
BN"3"24;
%"TAP"
"1","(-3325,5825)","0","mstr_standard","I167";
;
CDS_LIB"mstr_standard"
BODY_TYPE"PLUMBING"
HDL_TAP"TRUE";
"B \NAC \NWC"10;
"S \NAC"
BN"4"25;
%"TAP"
"1","(-3325,5725)","0","mstr_standard","I168";
;
CDS_LIB"mstr_standard"
BODY_TYPE"PLUMBING"
HDL_TAP"TRUE";
"B \NAC \NWC"10;
"S \NAC"
BN"6"27;
%"TAP"
"1","(-3325,5675)","0","mstr_standard","I169";
;
CDS_LIB"mstr_standard"
BODY_TYPE"PLUMBING"
HDL_TAP"TRUE";
"B \NAC \NWC"10;
"S \NAC"
BN"7"28;
%"TAP"
"1","(-3325,5525)","0","mstr_standard","I170";
;
CDS_LIB"mstr_standard"
BODY_TYPE"PLUMBING"
HDL_TAP"TRUE";
"B \NAC \NWC"10;
"S \NAC"
BN"9"30;
%"TAP"
"1","(-3325,5575)","0","mstr_standard","I171";
;
CDS_LIB"mstr_standard"
BODY_TYPE"PLUMBING"
HDL_TAP"TRUE";
"B \NAC \NWC"10;
"S \NAC"
BN"8"29;
%"TAP"
"1","(-3325,5475)","0","mstr_standard","I172";
;
CDS_LIB"mstr_standard"
BODY_TYPE"PLUMBING"
HDL_TAP"TRUE";
"B \NAC \NWC"10;
"S \NAC"
BN"10"31;
%"TAP"
"1","(-3325,5425)","0","mstr_standard","I173";
;
CDS_LIB"mstr_standard"
BODY_TYPE"PLUMBING"
HDL_TAP"TRUE";
"B \NAC \NWC"10;
"S \NAC"
BN"11"32;
%"TAP"
"1","(-3325,5275)","0","mstr_standard","I174";
;
CDS_LIB"mstr_standard"
BODY_TYPE"PLUMBING"
HDL_TAP"TRUE";
"B \NAC \NWC"10;
"S \NAC"
BN"14"35;
%"TAP"
"1","(-3325,5375)","0","mstr_standard","I175";
;
CDS_LIB"mstr_standard"
BODY_TYPE"PLUMBING"
HDL_TAP"TRUE";
"B \NAC \NWC"10;
"S \NAC"
BN"12"33;
%"TAP"
"1","(-3325,5325)","0","mstr_standard","I176";
;
CDS_LIB"mstr_standard"
BODY_TYPE"PLUMBING"
HDL_TAP"TRUE";
"B \NAC \NWC"10;
"S \NAC"
BN"13"34;
%"TAP"
"1","(-3325,5225)","0","mstr_standard","I177";
;
CDS_LIB"mstr_standard"
BODY_TYPE"PLUMBING"
HDL_TAP"TRUE";
"B \NAC \NWC"10;
"S \NAC"
BN"15"21;
%"TAP"
"1","(-3325,5125)","0","mstr_standard","I178";
;
CDS_LIB"mstr_standard"
BODY_TYPE"PLUMBING"
HDL_TAP"TRUE";
"B \NAC \NWC"10;
"S \NAC"
BN"16"20;
%"TAP"
"1","(-3325,5025)","0","mstr_standard","I179";
;
CDS_LIB"mstr_standard"
BODY_TYPE"PLUMBING"
HDL_TAP"TRUE";
"B \NAC \NWC"10;
"S \NAC"
BN"18"18;
%"TAP"
"1","(-3325,5075)","0","mstr_standard","I180";
;
CDS_LIB"mstr_standard"
BODY_TYPE"PLUMBING"
HDL_TAP"TRUE";
"B \NAC \NWC"10;
"S \NAC"
BN"17"19;
%"TAP"
"1","(-3325,4975)","0","mstr_standard","I181";
;
CDS_LIB"mstr_standard"
BODY_TYPE"PLUMBING"
HDL_TAP"TRUE";
"B \NAC \NWC"10;
"S \NAC"
BN"19"41;
%"TAP"
"1","(-3325,4875)","0","mstr_standard","I182";
;
CDS_LIB"mstr_standard"
BODY_TYPE"PLUMBING"
HDL_TAP"TRUE";
"B \NAC \NWC"10;
"S \NAC"
BN"21"23;
%"TAP"
"1","(-3325,4925)","0","mstr_standard","I183";
;
CDS_LIB"mstr_standard"
BODY_TYPE"PLUMBING"
HDL_TAP"TRUE";
"B \NAC \NWC"10;
"S \NAC"
BN"20"44;
%"TAP"
"1","(-3325,4675)","0","mstr_standard","I184";
;
CDS_LIB"mstr_standard"
BODY_TYPE"PLUMBING"
HDL_TAP"TRUE";
"B \NAC \NWC"10;
"S \NAC"
BN"24"47;
%"TAP"
"1","(-3325,4625)","0","mstr_standard","I185";
;
CDS_LIB"mstr_standard"
BODY_TYPE"PLUMBING"
HDL_TAP"TRUE";
"B \NAC \NWC"10;
"S \NAC"
BN"25"16;
%"TAP"
"1","(-3325,4775)","0","mstr_standard","I186";
;
CDS_LIB"mstr_standard"
BODY_TYPE"PLUMBING"
HDL_TAP"TRUE";
"B \NAC \NWC"10;
"S \NAC"
BN"23"46;
%"TAP"
"1","(-3325,4825)","0","mstr_standard","I187";
;
CDS_LIB"mstr_standard"
BODY_TYPE"PLUMBING"
HDL_TAP"TRUE";
"B \NAC \NWC"10;
"S \NAC"
BN"22"45;
%"TAP"
"1","(-3325,4575)","0","mstr_standard","I188";
;
CDS_LIB"mstr_standard"
BODY_TYPE"PLUMBING"
HDL_TAP"TRUE";
"B \NAC \NWC"10;
"S \NAC"
BN"26"48;
%"TAP"
"1","(-3325,4525)","0","mstr_standard","I189";
;
CDS_LIB"mstr_standard"
BODY_TYPE"PLUMBING"
HDL_TAP"TRUE";
"B \NAC \NWC"10;
"S \NAC"
BN"27"17;
%"TAP"
"1","(-3325,4475)","0","mstr_standard","I190";
;
CDS_LIB"mstr_standard"
BODY_TYPE"PLUMBING"
HDL_TAP"TRUE";
"B \NAC \NWC"10;
"S \NAC"
BN"28"51;
%"TAP"
"1","(-3325,4375)","0","mstr_standard","I191";
;
CDS_LIB"mstr_standard"
BODY_TYPE"PLUMBING"
HDL_TAP"TRUE";
"B \NAC \NWC"10;
"S \NAC"
BN"30"42;
%"TAP"
"1","(-3325,4425)","0","mstr_standard","I192";
;
CDS_LIB"mstr_standard"
BODY_TYPE"PLUMBING"
HDL_TAP"TRUE";
"B \NAC \NWC"10;
"S \NAC"
BN"29"40;
%"TAP"
"1","(-3325,4125)","0","mstr_standard","I193";
;
CDS_LIB"mstr_standard"
BODY_TYPE"PLUMBING"
HDL_TAP"TRUE";
"B \NAC \NWC"8;
"S \NAC"
BN"2"39;
%"TAP"
"1","(-3325,4225)","0","mstr_standard","I194";
;
CDS_LIB"mstr_standard"
BODY_TYPE"PLUMBING"
HDL_TAP"TRUE";
"B \NAC \NWC"8;
"S \NAC"
BN"0"49;
%"TAP"
"1","(-3325,4325)","0","mstr_standard","I195";
;
CDS_LIB"mstr_standard"
BODY_TYPE"PLUMBING"
HDL_TAP"TRUE";
"B \NAC \NWC"10;
"S \NAC"
BN"31"43;
%"TAP"
"1","(-3325,4175)","0","mstr_standard","I196";
;
CDS_LIB"mstr_standard"
BODY_TYPE"PLUMBING"
HDL_TAP"TRUE";
"B \NAC \NWC"8;
"S \NAC"
BN"1"50;
%"TAP"
"1","(-3325,3975)","0","mstr_standard","I198";
;
CDS_LIB"mstr_standard"
BODY_TYPE"PLUMBING"
HDL_TAP"TRUE";
"B \NAC \NWC"8;
"S \NAC"
BN"5"58;
%"TAP"
"1","(-3325,4075)","0","mstr_standard","I199";
;
CDS_LIB"mstr_standard"
BODY_TYPE"PLUMBING"
HDL_TAP"TRUE";
"B \NAC \NWC"8;
"S \NAC"
BN"3"54;
%"TAP"
"1","(-3325,4025)","0","mstr_standard","I200";
;
CDS_LIB"mstr_standard"
BODY_TYPE"PLUMBING"
HDL_TAP"TRUE";
"B \NAC \NWC"8;
"S \NAC"
BN"4"56;
%"TAP"
"1","(-3325,3925)","0","mstr_standard","I201";
;
CDS_LIB"mstr_standard"
BODY_TYPE"PLUMBING"
HDL_TAP"TRUE";
"B \NAC \NWC"8;
"S \NAC"
BN"6"60;
%"TAP"
"1","(-3325,3875)","0","mstr_standard","I202";
;
CDS_LIB"mstr_standard"
BODY_TYPE"PLUMBING"
HDL_TAP"TRUE";
"B \NAC \NWC"8;
"S \NAC"
BN"7"62;
%"TAP"
"1","(-3325,3775)","0","mstr_standard","I203";
;
CDS_LIB"mstr_standard"
BODY_TYPE"PLUMBING"
HDL_TAP"TRUE";
"B \NAC \NWC"8;
"S \NAC"
BN"8"64;
%"TAP"
"1","(-3325,3725)","0","mstr_standard","I204";
;
CDS_LIB"mstr_standard"
BODY_TYPE"PLUMBING"
HDL_TAP"TRUE";
"B \NAC \NWC"8;
"S \NAC"
BN"9"66;
%"TAP"
"1","(-3325,3675)","0","mstr_standard","I205";
;
CDS_LIB"mstr_standard"
BODY_TYPE"PLUMBING"
HDL_TAP"TRUE";
"B \NAC \NWC"8;
"S \NAC"
BN"10"69;
%"TAP"
"1","(-3325,3625)","0","mstr_standard","I206";
;
CDS_LIB"mstr_standard"
BODY_TYPE"PLUMBING"
HDL_TAP"TRUE";
"B \NAC \NWC"8;
"S \NAC"
BN"11"70;
%"TAP"
"1","(-3325,3475)","0","mstr_standard","I207";
;
CDS_LIB"mstr_standard"
BODY_TYPE"PLUMBING"
HDL_TAP"TRUE";
"B \NAC \NWC"8;
"S \NAC"
BN"14"55;
%"TAP"
"1","(-3325,3575)","0","mstr_standard","I208";
;
CDS_LIB"mstr_standard"
BODY_TYPE"PLUMBING"
HDL_TAP"TRUE";
"B \NAC \NWC"8;
"S \NAC"
BN"12"52;
%"TAP"
"1","(-3325,3525)","0","mstr_standard","I209";
;
CDS_LIB"mstr_standard"
BODY_TYPE"PLUMBING"
HDL_TAP"TRUE";
"B \NAC \NWC"8;
"S \NAC"
BN"13"53;
%"TAP"
"1","(-3325,3425)","0","mstr_standard","I210";
;
CDS_LIB"mstr_standard"
BODY_TYPE"PLUMBING"
HDL_TAP"TRUE";
"B \NAC \NWC"8;
"S \NAC"
BN"15"57;
%"TAP"
"1","(-3325,3225)","0","mstr_standard","I211";
;
CDS_LIB"mstr_standard"
BODY_TYPE"PLUMBING"
HDL_TAP"TRUE";
"B \NAC \NWC"8;
"S \NAC"
BN"18"63;
%"TAP"
"1","(-3325,3275)","0","mstr_standard","I212";
;
CDS_LIB"mstr_standard"
BODY_TYPE"PLUMBING"
HDL_TAP"TRUE";
"B \NAC \NWC"8;
"S \NAC"
BN"17"61;
%"TAP"
"1","(-3325,3325)","0","mstr_standard","I213";
;
CDS_LIB"mstr_standard"
BODY_TYPE"PLUMBING"
HDL_TAP"TRUE";
"B \NAC \NWC"8;
"S \NAC"
BN"16"59;
%"TAP"
"1","(-3325,3075)","0","mstr_standard","I214";
;
CDS_LIB"mstr_standard"
BODY_TYPE"PLUMBING"
HDL_TAP"TRUE";
"B \NAC \NWC"8;
"S \NAC"
BN"21"68;
%"TAP"
"1","(-3325,3175)","0","mstr_standard","I215";
;
CDS_LIB"mstr_standard"
BODY_TYPE"PLUMBING"
HDL_TAP"TRUE";
"B \NAC \NWC"8;
"S \NAC"
BN"19"65;
%"TAP"
"1","(-3325,3125)","0","mstr_standard","I216";
;
CDS_LIB"mstr_standard"
BODY_TYPE"PLUMBING"
HDL_TAP"TRUE";
"B \NAC \NWC"8;
"S \NAC"
BN"20"67;
%"TAP"
"1","(-3325,2975)","0","mstr_standard","I217";
;
CDS_LIB"mstr_standard"
BODY_TYPE"PLUMBING"
HDL_TAP"TRUE";
"B \NAC \NWC"8;
"S \NAC"
BN"23"71;
%"TAP"
"1","(-3325,2875)","0","mstr_standard","I218";
;
CDS_LIB"mstr_standard"
BODY_TYPE"PLUMBING"
HDL_TAP"TRUE";
"B \NAC \NWC"8;
"S \NAC"
BN"24"72;
%"TAP"
"1","(-3325,3025)","0","mstr_standard","I219";
;
CDS_LIB"mstr_standard"
BODY_TYPE"PLUMBING"
HDL_TAP"TRUE";
"B \NAC \NWC"8;
"S \NAC"
BN"22"88;
%"TAP"
"1","(-3325,2825)","0","mstr_standard","I220";
;
CDS_LIB"mstr_standard"
BODY_TYPE"PLUMBING"
HDL_TAP"TRUE";
"B \NAC \NWC"8;
"S \NAC"
BN"25"73;
%"TAP"
"1","(-3325,2775)","0","mstr_standard","I221";
;
CDS_LIB"mstr_standard"
BODY_TYPE"PLUMBING"
HDL_TAP"TRUE";
"B \NAC \NWC"8;
"S \NAC"
BN"26"74;
%"TAP"
"1","(-3325,2725)","0","mstr_standard","I222";
;
CDS_LIB"mstr_standard"
BODY_TYPE"PLUMBING"
HDL_TAP"TRUE";
"B \NAC \NWC"8;
"S \NAC"
BN"27"75;
%"TAP"
"1","(-3325,2675)","0","mstr_standard","I223";
;
CDS_LIB"mstr_standard"
BODY_TYPE"PLUMBING"
HDL_TAP"TRUE";
"B \NAC \NWC"8;
"S \NAC"
BN"28"76;
%"TAP"
"1","(-3325,2575)","0","mstr_standard","I224";
;
CDS_LIB"mstr_standard"
BODY_TYPE"PLUMBING"
HDL_TAP"TRUE";
"B \NAC \NWC"8;
"S \NAC"
BN"30"83;
%"TAP"
"1","(-3325,2625)","0","mstr_standard","I225";
;
CDS_LIB"mstr_standard"
BODY_TYPE"PLUMBING"
HDL_TAP"TRUE";
"B \NAC \NWC"8;
"S \NAC"
BN"29"77;
%"TAP"
"1","(-3325,2325)","0","mstr_standard","I226";
;
CDS_LIB"mstr_standard"
BODY_TYPE"PLUMBING"
HDL_TAP"TRUE";
"B \NAC \NWC"9;
"S \NAC"
BN"2"80;
%"TAP"
"1","(-3325,2375)","0","mstr_standard","I227";
;
CDS_LIB"mstr_standard"
BODY_TYPE"PLUMBING"
HDL_TAP"TRUE";
"B \NAC \NWC"9;
"S \NAC"
BN"1"79;
%"TAP"
"1","(-3325,2425)","0","mstr_standard","I228";
;
CDS_LIB"mstr_standard"
BODY_TYPE"PLUMBING"
HDL_TAP"TRUE";
"B \NAC \NWC"9;
"S \NAC"
BN"0"78;
%"TAP"
"1","(-3325,2525)","0","mstr_standard","I229";
;
CDS_LIB"mstr_standard"
BODY_TYPE"PLUMBING"
HDL_TAP"TRUE";
"B \NAC \NWC"8;
"S \NAC"
BN"31"85;
%"TAP"
"1","(-3325,2225)","0","mstr_standard","I230";
;
CDS_LIB"mstr_standard"
BODY_TYPE"PLUMBING"
HDL_TAP"TRUE";
"B \NAC \NWC"9;
"S \NAC"
BN"4"82;
%"TAP"
"1","(-3325,2275)","0","mstr_standard","I231";
;
CDS_LIB"mstr_standard"
BODY_TYPE"PLUMBING"
HDL_TAP"TRUE";
"B \NAC \NWC"9;
"S \NAC"
BN"3"81;
%"TAP"
"1","(-3325,2175)","0","mstr_standard","I232";
;
CDS_LIB"mstr_standard"
BODY_TYPE"PLUMBING"
HDL_TAP"TRUE";
"B \NAC \NWC"9;
"S \NAC"
BN"5"84;
%"TAP"
"1","(-3325,2125)","0","mstr_standard","I233";
;
CDS_LIB"mstr_standard"
BODY_TYPE"PLUMBING"
HDL_TAP"TRUE";
"B \NAC \NWC"9;
"S \NAC"
BN"6"86;
%"TAP"
"1","(-3325,2075)","0","mstr_standard","I234";
;
CDS_LIB"mstr_standard"
BODY_TYPE"PLUMBING"
HDL_TAP"TRUE";
"B \NAC \NWC"9;
"S \NAC"
BN"7"87;
%"TAP"
"1","(-3325,1825)","0","mstr_standard","I236";
;
CDS_LIB"mstr_standard"
BODY_TYPE"PLUMBING"
HDL_TAP"TRUE";
"B \NAC \NWC"7;
"S \NAC"
BN"3"89;
%"TAP"
"1","(-3325,1875)","0","mstr_standard","I237";
;
CDS_LIB"mstr_standard"
BODY_TYPE"PLUMBING"
HDL_TAP"TRUE";
"B \NAC \NWC"7;
"S \NAC"
BN"2"96;
%"TAP"
"1","(-3325,1975)","0","mstr_standard","I238";
;
CDS_LIB"mstr_standard"
BODY_TYPE"PLUMBING"
HDL_TAP"TRUE";
"B \NAC \NWC"7;
"S \NAC"
BN"0"94;
%"TAP"
"1","(-3325,1925)","0","mstr_standard","I239";
;
CDS_LIB"mstr_standard"
BODY_TYPE"PLUMBING"
HDL_TAP"TRUE";
"B \NAC \NWC"7;
"S \NAC"
BN"1"95;
%"TAP"
"1","(-3325,1675)","0","mstr_standard","I240";
;
CDS_LIB"mstr_standard"
BODY_TYPE"PLUMBING"
HDL_TAP"TRUE";
"B \NAC \NWC"7;
"S \NAC"
BN"6"92;
%"TAP"
"1","(-3325,1775)","0","mstr_standard","I241";
;
CDS_LIB"mstr_standard"
BODY_TYPE"PLUMBING"
HDL_TAP"TRUE";
"B \NAC \NWC"7;
"S \NAC"
BN"4"90;
%"TAP"
"1","(-3325,1725)","0","mstr_standard","I242";
;
CDS_LIB"mstr_standard"
BODY_TYPE"PLUMBING"
HDL_TAP"TRUE";
"B \NAC \NWC"7;
"S \NAC"
BN"5"91;
%"TAP"
"1","(-3325,1625)","0","mstr_standard","I243";
;
CDS_LIB"mstr_standard"
BODY_TYPE"PLUMBING"
HDL_TAP"TRUE";
"B \NAC \NWC"7;
"S \NAC"
BN"7"93;
%"TAP"
"1","(-5750,6025)","2","mstr_standard","I244";
;
CDS_LIB"mstr_standard"
BODY_TYPE"PLUMBING"
HDL_TAP"TRUE";
"B \NAC \NWC"6;
"S \NAC"
BN"0"113;
%"TAP"
"1","(-5750,5925)","2","mstr_standard","I245";
;
CDS_LIB"mstr_standard"
BODY_TYPE"PLUMBING"
HDL_TAP"TRUE";
"B \NAC \NWC"6;
"S \NAC"
BN"1"22;
%"TAP"
"1","(-5750,5825)","2","mstr_standard","I246";
;
CDS_LIB"mstr_standard"
BODY_TYPE"PLUMBING"
HDL_TAP"TRUE";
"B \NAC \NWC"6;
"S \NAC"
BN"2"99;
%"TAP"
"1","(-5750,5725)","2","mstr_standard","I247";
;
CDS_LIB"mstr_standard"
BODY_TYPE"PLUMBING"
HDL_TAP"TRUE";
"B \NAC \NWC"6;
"S \NAC"
BN"3"101;
%"TAP"
"1","(-5950,5975)","2","mstr_standard","I248";
;
CDS_LIB"mstr_standard"
BODY_TYPE"PLUMBING"
HDL_TAP"TRUE";
"B \NAC \NWC"5;
"S \NAC"
BN"0"109;
%"TAP"
"1","(-5950,5875)","2","mstr_standard","I249";
;
CDS_LIB"mstr_standard"
BODY_TYPE"PLUMBING"
HDL_TAP"TRUE";
"B \NAC \NWC"5;
"S \NAC"
BN"1"110;
%"TAP"
"1","(-5950,5775)","2","mstr_standard","I250";
;
CDS_LIB"mstr_standard"
BODY_TYPE"PLUMBING"
HDL_TAP"TRUE";
"B \NAC \NWC"5;
"S \NAC"
BN"2"13;
%"TAP"
"1","(-5950,5675)","2","mstr_standard","I251";
;
CDS_LIB"mstr_standard"
BODY_TYPE"PLUMBING"
HDL_TAP"TRUE";
"B \NAC \NWC"5;
"S \NAC"
BN"3"111;
%"TAP"
"1","(-5750,5525)","2","mstr_standard","I252";
;
CDS_LIB"mstr_standard"
BODY_TYPE"PLUMBING"
HDL_TAP"TRUE";
"B \NAC \NWC"6;
"S \NAC"
BN"5"104;
%"TAP"
"1","(-5750,5625)","2","mstr_standard","I253";
;
CDS_LIB"mstr_standard"
BODY_TYPE"PLUMBING"
HDL_TAP"TRUE";
"B \NAC \NWC"6;
"S \NAC"
BN"4"103;
%"TAP"
"1","(-5750,5425)","2","mstr_standard","I254";
;
CDS_LIB"mstr_standard"
BODY_TYPE"PLUMBING"
HDL_TAP"TRUE";
"B \NAC \NWC"6;
"S \NAC"
BN"6"105;
%"TAP"
"1","(-5750,5325)","2","mstr_standard","I255";
;
CDS_LIB"mstr_standard"
BODY_TYPE"PLUMBING"
HDL_TAP"TRUE";
"B \NAC \NWC"6;
"S \NAC"
BN"7"106;
%"TAP"
"1","(-5750,5125)","2","mstr_standard","I256";
;
CDS_LIB"mstr_standard"
BODY_TYPE"PLUMBING"
HDL_TAP"TRUE";
"B \NAC \NWC"6;
"S \NAC"
BN"9"108;
%"TAP"
"1","(-5750,5225)","2","mstr_standard","I257";
;
CDS_LIB"mstr_standard"
BODY_TYPE"PLUMBING"
HDL_TAP"TRUE";
"B \NAC \NWC"6;
"S \NAC"
BN"8"107;
%"TAP"
"1","(-5950,5575)","2","mstr_standard","I258";
;
CDS_LIB"mstr_standard"
BODY_TYPE"PLUMBING"
HDL_TAP"TRUE";
"B \NAC \NWC"5;
"S \NAC"
BN"4"112;
%"TAP"
"1","(-5950,5475)","2","mstr_standard","I259";
;
CDS_LIB"mstr_standard"
BODY_TYPE"PLUMBING"
HDL_TAP"TRUE";
"B \NAC \NWC"5;
"S \NAC"
BN"5"97;
%"TAP"
"1","(-5950,5375)","2","mstr_standard","I260";
;
CDS_LIB"mstr_standard"
BODY_TYPE"PLUMBING"
HDL_TAP"TRUE";
"B \NAC \NWC"5;
"S \NAC"
BN"6"98;
%"TAP"
"1","(-5950,5275)","2","mstr_standard","I261";
;
CDS_LIB"mstr_standard"
BODY_TYPE"PLUMBING"
HDL_TAP"TRUE";
"B \NAC \NWC"5;
"S \NAC"
BN"7"100;
%"TAP"
"1","(-5950,5175)","2","mstr_standard","I262";
;
CDS_LIB"mstr_standard"
BODY_TYPE"PLUMBING"
HDL_TAP"TRUE";
"B \NAC \NWC"5;
"S \NAC"
BN"8"102;
%"TAP"
"1","(-5750,4875)","2","mstr_standard","I263";
;
CDS_LIB"mstr_standard"
BODY_TYPE"PLUMBING"
HDL_TAP"TRUE";
"B \NAC \NWC"1;
"S \NAC"
BN"1"122;
%"TAP"
"1","(-5750,4975)","2","mstr_standard","I264";
;
CDS_LIB"mstr_standard"
BODY_TYPE"PLUMBING"
HDL_TAP"TRUE";
"B \NAC \NWC"1;
"S \NAC"
BN"0"120;
%"TAP"
"1","(-5750,4775)","2","mstr_standard","I265";
;
CDS_LIB"mstr_standard"
BODY_TYPE"PLUMBING"
HDL_TAP"TRUE";
"B \NAC \NWC"1;
"S \NAC"
BN"2"124;
%"TAP"
"1","(-5750,4675)","2","mstr_standard","I266";
;
CDS_LIB"mstr_standard"
BODY_TYPE"PLUMBING"
HDL_TAP"TRUE";
"B \NAC \NWC"1;
"S \NAC"
BN"3"126;
%"TAP"
"1","(-5950,5075)","2","mstr_standard","I267";
;
CDS_LIB"mstr_standard"
BODY_TYPE"PLUMBING"
HDL_TAP"TRUE";
"B \NAC \NWC"5;
"S \NAC"
BN"9"118;
%"TAP"
"1","(-5950,4925)","2","mstr_standard","I268";
;
CDS_LIB"mstr_standard"
BODY_TYPE"PLUMBING"
HDL_TAP"TRUE";
"B \NAC \NWC"4;
"S \NAC"
BN"0"114;
%"TAP"
"1","(-5950,4825)","2","mstr_standard","I269";
;
CDS_LIB"mstr_standard"
BODY_TYPE"PLUMBING"
HDL_TAP"TRUE";
"B \NAC \NWC"4;
"S \NAC"
BN"1"115;
%"TAP"
"1","(-5950,4725)","2","mstr_standard","I270";
;
CDS_LIB"mstr_standard"
BODY_TYPE"PLUMBING"
HDL_TAP"TRUE";
"B \NAC \NWC"4;
"S \NAC"
BN"2"116;
%"TAP"
"1","(-5950,4625)","2","mstr_standard","I271";
;
CDS_LIB"mstr_standard"
BODY_TYPE"PLUMBING"
HDL_TAP"TRUE";
"B \NAC \NWC"4;
"S \NAC"
BN"3"117;
%"TAP"
"1","(-5750,4575)","2","mstr_standard","I272";
;
CDS_LIB"mstr_standard"
BODY_TYPE"PLUMBING"
HDL_TAP"TRUE";
"B \NAC \NWC"1;
"S \NAC"
BN"4"128;
%"TAP"
"1","(-5750,4475)","2","mstr_standard","I273";
;
CDS_LIB"mstr_standard"
BODY_TYPE"PLUMBING"
HDL_TAP"TRUE";
"B \NAC \NWC"1;
"S \NAC"
BN"5"129;
%"TAP"
"1","(-5750,4375)","2","mstr_standard","I274";
;
CDS_LIB"mstr_standard"
BODY_TYPE"PLUMBING"
HDL_TAP"TRUE";
"B \NAC \NWC"1;
"S \NAC"
BN"6"130;
%"TAP"
"1","(-5750,4275)","2","mstr_standard","I275";
;
CDS_LIB"mstr_standard"
BODY_TYPE"PLUMBING"
HDL_TAP"TRUE";
"B \NAC \NWC"1;
"S \NAC"
BN"7"14;
%"TAP"
"1","(-5750,4175)","2","mstr_standard","I276";
;
CDS_LIB"mstr_standard"
BODY_TYPE"PLUMBING"
HDL_TAP"TRUE";
"B \NAC \NWC"1;
"S \NAC"
BN"8"131;
%"TAP"
"1","(-5950,4525)","2","mstr_standard","I277";
;
CDS_LIB"mstr_standard"
BODY_TYPE"PLUMBING"
HDL_TAP"TRUE";
"B \NAC \NWC"4;
"S \NAC"
BN"4"119;
%"TAP"
"1","(-5950,4425)","2","mstr_standard","I278";
;
CDS_LIB"mstr_standard"
BODY_TYPE"PLUMBING"
HDL_TAP"TRUE";
"B \NAC \NWC"4;
"S \NAC"
BN"5"121;
%"TAP"
"1","(-5950,4325)","2","mstr_standard","I279";
;
CDS_LIB"mstr_standard"
BODY_TYPE"PLUMBING"
HDL_TAP"TRUE";
"B \NAC \NWC"4;
"S \NAC"
BN"6"123;
%"TAP"
"1","(-5950,4225)","2","mstr_standard","I280";
;
CDS_LIB"mstr_standard"
BODY_TYPE"PLUMBING"
HDL_TAP"TRUE";
"B \NAC \NWC"4;
"S \NAC"
BN"7"125;
%"TAP"
"1","(-5950,4125)","2","mstr_standard","I281";
;
CDS_LIB"mstr_standard"
BODY_TYPE"PLUMBING"
HDL_TAP"TRUE";
"B \NAC \NWC"4;
"S \NAC"
BN"8"127;
%"TAP"
"1","(-5750,4075)","2","mstr_standard","I286";
;
CDS_LIB"mstr_standard"
BODY_TYPE"PLUMBING"
HDL_TAP"TRUE";
"B \NAC \NWC"1;
"S \NAC"
BN"9"146;
%"TAP"
"1","(-5950,3825)","2","mstr_standard","I287";
;
CDS_LIB"mstr_standard"
BODY_TYPE"PLUMBING"
HDL_TAP"TRUE";
"B \NAC \NWC"3;
"S \NAC"
BN"1"134;
%"TAP"
"1","(-5950,4025)","2","mstr_standard","I288";
;
CDS_LIB"mstr_standard"
BODY_TYPE"PLUMBING"
HDL_TAP"TRUE";
"B \NAC \NWC"4;
"S \NAC"
BN"9"139;
%"TAP"
"1","(-5950,3875)","2","mstr_standard","I289";
;
CDS_LIB"mstr_standard"
BODY_TYPE"PLUMBING"
HDL_TAP"TRUE";
"B \NAC \NWC"3;
"S \NAC"
BN"0"132;
%"TAP"
"1","(-5950,3775)","2","mstr_standard","I290";
;
CDS_LIB"mstr_standard"
BODY_TYPE"PLUMBING"
HDL_TAP"TRUE";
"B \NAC \NWC"3;
"S \NAC"
BN"2"136;
%"TAP"
"1","(-5950,3725)","2","mstr_standard","I291";
;
CDS_LIB"mstr_standard"
BODY_TYPE"PLUMBING"
HDL_TAP"TRUE";
"B \NAC \NWC"3;
"S \NAC"
BN"3"138;
%"TAP"
"1","(-5950,3675)","2","mstr_standard","I292";
;
CDS_LIB"mstr_standard"
BODY_TYPE"PLUMBING"
HDL_TAP"TRUE";
"B \NAC \NWC"3;
"S \NAC"
BN"4"140;
%"TAP"
"1","(-5950,3625)","2","mstr_standard","I293";
;
CDS_LIB"mstr_standard"
BODY_TYPE"PLUMBING"
HDL_TAP"TRUE";
"B \NAC \NWC"3;
"S \NAC"
BN"5"142;
%"TAP"
"1","(-5950,3575)","2","mstr_standard","I294";
;
CDS_LIB"mstr_standard"
BODY_TYPE"PLUMBING"
HDL_TAP"TRUE";
"B \NAC \NWC"3;
"S \NAC"
BN"6"143;
%"TAP"
"1","(-5950,3425)","2","mstr_standard","I295";
;
CDS_LIB"mstr_standard"
BODY_TYPE"PLUMBING"
HDL_TAP"TRUE";
"B \NAC \NWC"2;
"S \NAC"
BN"1"135;
%"TAP"
"1","(-5950,3475)","2","mstr_standard","I296";
;
CDS_LIB"mstr_standard"
BODY_TYPE"PLUMBING"
HDL_TAP"TRUE";
"B \NAC \NWC"2;
"S \NAC"
BN"0"133;
%"TAP"
"1","(-5950,3325)","2","mstr_standard","I297";
;
CDS_LIB"mstr_standard"
BODY_TYPE"PLUMBING"
HDL_TAP"TRUE";
"B \NAC \NWC"2;
"S \NAC"
BN"3"145;
%"TAP"
"1","(-5950,3375)","2","mstr_standard","I298";
;
CDS_LIB"mstr_standard"
BODY_TYPE"PLUMBING"
HDL_TAP"TRUE";
"B \NAC \NWC"2;
"S \NAC"
BN"2"137;
%"TAP"
"1","(-5950,3275)","2","mstr_standard","I299";
;
CDS_LIB"mstr_standard"
BODY_TYPE"PLUMBING"
HDL_TAP"TRUE";
"B \NAC \NWC"2;
"S \NAC"
BN"4"141;
%"TAP"
"1","(-5950,3225)","2","mstr_standard","I300";
;
CDS_LIB"mstr_standard"
BODY_TYPE"PLUMBING"
HDL_TAP"TRUE";
"B \NAC \NWC"2;
"S \NAC"
BN"5"15;
%"TAP"
"1","(-5950,3175)","2","mstr_standard","I301";
;
CDS_LIB"mstr_standard"
BODY_TYPE"PLUMBING"
HDL_TAP"TRUE";
"B \NAC \NWC"2;
"S \NAC"
BN"6"144;
%"Q_RES"
"1","(-6875,2175)","0","pure_quanta","I314";
;
LOCATION"R378"
$SEC"1"
CDS_SEC"1"
PACK_TYPE"0402LF"
TOLERANCE"1%"
VALUE"15"
MATERIAL"CHIP"
WATTAGE"1/16W"
CDS_LIB"pure_quanta"
PART_NUMBER"CS01502FB03";
"B"
$PN"2"12;
"A"
$PN"1"11;
END.
